(kicad_pcb
	(version 20241229)
	(generator "pcbnew")
	(generator_version "9.0")
	(general
		(thickness 1.62)
		(legacy_teardrops no)
	)
	(paper "A3")
	(title_block
		(title "COM Express 7 Baseboard")
		(date "2025-02-04")
		(rev "1.1.2")
		(company "Antmicro Ltd")
		(comment 1 "www.antmicro.com")
		(comment 9 "footprints 78-81 of 802")
	)
	(layers
		(0 "F.Cu" signal)
		(4 "In1.Cu" signal)
		(6 "In2.Cu" signal)
		(8 "In3.Cu" signal)
		(10 "In4.Cu" signal)
		(12 "In5.Cu" signal)
		(14 "In6.Cu" signal)
		(2 "B.Cu" signal)
		(9 "F.Adhes" user "F.Adhesive")
		(11 "B.Adhes" user "B.Adhesive")
		(13 "F.Paste" user)
		(15 "B.Paste" user)
		(5 "F.SilkS" user "F.Silkscreen")
		(7 "B.SilkS" user "B.Silkscreen")
		(1 "F.Mask" user)
		(3 "B.Mask" user)
		(17 "Dwgs.User" user "User.Drawings")
		(19 "Cmts.User" user "User.Comments")
		(21 "Eco1.User" user "User.Eco1")
		(23 "Eco2.User" user "User.Eco2")
		(25 "Edge.Cuts" user)
		(27 "Margin" user)
		(31 "F.CrtYd" user "F.Courtyard")
		(29 "B.CrtYd" user "B.Courtyard")
		(35 "F.Fab" user)
		(33 "B.Fab" user)
	)
	(footprint "antmicro-footprints:LED_0603_1608Metric_G"
		(layer "F.Cu")
		(at 186.70861 74.802163 90)
		(descr "LED SMD 0603 Green")
		(tags "LED SMD 0603 Green")
		(property "Reference" "D31"
			(at -1.1 -0.55 90)
			(layer "F.SilkS")
			(effects
				(font
					(size 0.7 0.7)
					(thickness 0.15)
				)
				(justify left bottom)
			)
		)
		(property "Value" "LED_G_0603_LTST-C190GKT"
			(at -0.001 1.599 90)
			(layer "F.Fab")
			(effects
				(font
					(size 0.7 0.7)
					(thickness 0.15)
				)
				(justify left bottom)
			)
		)
		(property "Datasheet" "https://media.digikey.com/pdf/Data%20Sheets/Lite-On%20PDFs/LTST-C190GKT.pdf"
			(at 0 0 90)
			(layer "F.Fab")
			(hide yes)
			(effects
				(font
					(size 1.27 1.27)
					(thickness 0.15)
				)
			)
		)
		(property "Author" "Antmicro"
			(at 261.510773 -111.906447 0)
			(layer "F.Fab")
			(hide yes)
			(effects
				(font
					(size 1 1)
					(thickness 0.15)
				)
			)
		)
		(property "Color" "Green"
			(at 261.510773 -111.906447 0)
			(layer "F.Fab")
			(hide yes)
			(effects
				(font
					(size 1 1)
					(thickness 0.15)
				)
			)
		)
		(property "License" "Apache-2.0"
			(at 261.510773 -111.906447 0)
			(layer "F.Fab")
			(hide yes)
			(effects
				(font
					(size 1 1)
					(thickness 0.15)
				)
			)
		)
		(property "MPN" "LTST-C190GKT"
			(at 261.510773 -111.906447 0)
			(layer "F.Fab")
			(hide yes)
			(effects
				(font
					(size 1 1)
					(thickness 0.15)
				)
			)
		)
		(property "Manufacturer" "Lite-On"
			(at 261.510773 -111.906447 0)
			(layer "F.Fab")
			(hide yes)
			(effects
				(font
					(size 1 1)
					(thickness 0.15)
				)
			)
		)
		(property "Public" "False"
			(at 261.510773 -111.906447 0)
			(layer "F.Fab")
			(hide yes)
			(effects
				(font
					(size 1 1)
					(thickness 0.15)
				)
			)
		)
		(sheetname "Power")
		(sheetfile "power.kicad_sch")
		(attr smd)
		(fp_line
			(start 0.22 -0.35)
			(end -0.22 -0.35)
			(stroke
				(width 0.15)
				(type solid)
			)
			(layer "F.SilkS")
		)
		(fp_line
			(start -1.18 -0.319)
			(end -1.18 0.321)
			(stroke
				(width 0.15)
				(type solid)
			)
			(layer "F.SilkS")
		)
		(fp_line
			(start 0.105328 0.001008)
			(end 0.24 0.001)
			(stroke
				(width 0.1)
				(type solid)
			)
			(layer "F.SilkS")
		)
		(fp_line
			(start -0.094672 0.001008)
			(end 0.105328 -0.198992)
			(stroke
				(width 0.1)
				(type solid)
			)
			(layer "F.SilkS")
		)
		(fp_line
			(start -0.094672 0.001008)
			(end -0.24 0.001008)
			(stroke
				(width 0.1)
				(type solid)
			)
			(layer "F.SilkS")
		)
		(fp_line
			(start 0.105328 0.201008)
			(end 0.105328 -0.198992)
			(stroke
				(width 0.1)
				(type solid)
			)
			(layer "F.SilkS")
		)
		(fp_line
			(start 0.105328 0.201008)
			(end -0.094672 0.001008)
			(stroke
				(width 0.1)
				(type solid)
			)
			(layer "F.SilkS")
		)
		(fp_line
			(start -0.094672 0.201008)
			(end -0.094672 -0.198992)
			(stroke
				(width 0.1)
				(type solid)
			)
			(layer "F.SilkS")
		)
		(fp_line
			(start 0.22 0.35)
			(end -0.22 0.35)
			(stroke
				(width 0.15)
				(type solid)
			)
			(layer "F.SilkS")
		)
		(fp_rect
			(start 1.25 0.65)
			(end -1.25 -0.65)
			(stroke
				(width 0.05)
				(type solid)
			)
			(fill no)
			(layer "F.CrtYd")
		)
		(fp_line
			(start 0.201 -0.202)
			(end -0.101 0)
			(stroke
				(width 0.15)
				(type solid)
			)
			(layer "F.Fab")
		)
		(fp_line
			(start -0.199 -0.202)
			(end -0.199 0.1)
			(stroke
				(width 0.15)
				(type solid)
			)
			(layer "F.Fab")
		)
		(fp_line
			(start 0.599 0)
			(end 0.201 0)
			(stroke
				(width 0.15)
				(type solid)
			)
			(layer "F.Fab")
		)
		(fp_line
			(start 0.201 0)
			(end 0.201 -0.202)
			(stroke
				(width 0.15)
				(type solid)
			)
			(layer "F.Fab")
		)
		(fp_line
			(start -0.101 0)
			(end 0.201 0.2)
			(stroke
				(width 0.15)
				(type solid)
			)
			(layer "F.Fab")
		)
		(fp_line
			(start -0.199 0)
			(end -0.597 0)
			(stroke
				(width 0.15)
				(type solid)
			)
			(layer "F.Fab")
		)
		(fp_line
			(start 0.201 0.2)
			(end 0.201 0)
			(stroke
				(width 0.15)
				(type solid)
			)
			(layer "F.Fab")
		)
		(fp_line
			(start -0.199 0.2)
			(end -0.199 0.1)
			(stroke
				(width 0.15)
				(type solid)
			)
			(layer "F.Fab")
		)
		(fp_rect
			(start 0.848 0.4)
			(end -0.85 -0.402)
			(stroke
				(width 0.15)
				(type solid)
			)
			(fill no)
			(layer "F.Fab")
		)
		(pad "1" smd roundrect
			(at -0.7 0 270)
			(size 0.8 1)
			(layers "F.Cu" "F.Mask" "F.Paste")
			(roundrect_rratio 0.2)
			(net 983 "Net-(D31-C)")
			(pinfunction "C")
			(pintype "passive")
			(teardrops
				(best_length_ratio 0.2)
				(max_length 1)
				(best_width_ratio 0.9)
				(max_width 2)
				(curved_edges yes)
				(filter_ratio 0.9)
				(enabled yes)
				(allow_two_segments yes)
				(prefer_zone_connections yes)
			)
		)
		(pad "2" smd roundrect
			(at 0.7 0 270)
			(size 0.8 1)
			(layers "F.Cu" "F.Mask" "F.Paste")
			(roundrect_rratio 0.2)
			(net 62 "+12V_AON")
			(pinfunction "A")
			(pintype "passive")
			(teardrops
				(best_length_ratio 0.2)
				(max_length 1)
				(best_width_ratio 0.9)
				(max_width 2)
				(curved_edges yes)
				(filter_ratio 0.9)
				(enabled yes)
				(allow_two_segments yes)
				(prefer_zone_connections yes)
			)
		)
	)
	(footprint "antmicro-footprints:SOT-23-3"
		(layer "F.Cu")
		(at 238.41 127.49 90)
		(property "Reference" "D35"
			(at -1.8 -1.8 90)
			(layer "F.SilkS")
			(effects
				(font
					(size 0.7 0.7)
					(thickness 0.15)
				)
				(justify left bottom)
			)
		)
		(property "Value" "BAT54C"
			(at -1.9 2.7 90)
			(layer "F.Fab")
			(effects
				(font
					(size 0.7 0.7)
					(thickness 0.15)
				)
				(justify left bottom)
			)
		)
		(property "Datasheet" "https://diotec.com/request/datasheet/bat54.pdf"
			(at 0 0 90)
			(layer "F.Fab")
			(hide yes)
			(effects
				(font
					(size 1.27 1.27)
					(thickness 0.15)
				)
			)
		)
		(property "MPN" "BAT54C"
			(at 0 0 90)
			(unlocked yes)
			(layer "F.Fab")
			(hide yes)
			(effects
				(font
					(size 1 1)
					(thickness 0.15)
				)
			)
		)
		(property "Manufacturer" "Diotec Semiconductor"
			(at 0 0 90)
			(unlocked yes)
			(layer "F.Fab")
			(hide yes)
			(effects
				(font
					(size 1 1)
					(thickness 0.15)
				)
			)
		)
		(property "Author" "Antmicro"
			(at 0 0 90)
			(unlocked yes)
			(layer "F.Fab")
			(hide yes)
			(effects
				(font
					(size 1 1)
					(thickness 0.15)
				)
			)
		)
		(property "License" "Apache-2.0"
			(at 0 0 90)
			(unlocked yes)
			(layer "F.Fab")
			(hide yes)
			(effects
				(font
					(size 1 1)
					(thickness 0.15)
				)
			)
		)
		(sheetname "Com Express 7 MGMT")
		(sheetfile "com_express_7_mgmt.kicad_sch")
		(attr smd)
		(fp_line
			(start 0.7 -1.5)
			(end -0.7 -1.5)
			(stroke
				(width 0.15)
				(type solid)
			)
			(layer "F.SilkS")
		)
		(fp_line
			(start -0.85 -1.35)
			(end -0.7 -1.5)
			(stroke
				(width 0.15)
				(type solid)
			)
			(layer "F.SilkS")
		)
		(fp_line
			(start -1.45 -1.35)
			(end -0.85 -1.35)
			(stroke
				(width 0.15)
				(type solid)
			)
			(layer "F.SilkS")
		)
		(fp_line
			(start 0.7 -0.4)
			(end 0.7 -1.5)
			(stroke
				(width 0.15)
				(type solid)
			)
			(layer "F.SilkS")
		)
		(fp_line
			(start 0.7 0.4)
			(end 0.7 1.5)
			(stroke
				(width 0.15)
				(type solid)
			)
			(layer "F.SilkS")
		)
		(fp_line
			(start 0.7 1.5)
			(end -0.7 1.5)
			(stroke
				(width 0.15)
				(type solid)
			)
			(layer "F.SilkS")
		)
		(fp_line
			(start -0.7 1.5)
			(end -0.7 1.35)
			(stroke
				(width 0.15)
				(type solid)
			)
			(layer "F.SilkS")
		)
		(fp_line
			(start 0.825 -1.6)
			(end 0.825 -0.45)
			(stroke
				(width 0.05)
				(type solid)
			)
			(layer "F.CrtYd")
		)
		(fp_line
			(start -0.9 -1.6)
			(end 0.825 -1.6)
			(stroke
				(width 0.05)
				(type solid)
			)
			(layer "F.CrtYd")
		)
		(fp_line
			(start -0.9 -1.6)
			(end -0.9 -1.4)
			(stroke
				(width 0.05)
				(type solid)
			)
			(layer "F.CrtYd")
		)
		(fp_line
			(start -0.9 -1.4)
			(end -1.75 -1.4)
			(stroke
				(width 0.05)
				(type solid)
			)
			(layer "F.CrtYd")
		)
		(fp_line
			(start -0.85 -0.5)
			(end -1.75 -0.5)
			(stroke
				(width 0.05)
				(type solid)
			)
			(layer "F.CrtYd")
		)
		(fp_line
			(start -1.75 -0.5)
			(end -1.75 -1.4)
			(stroke
				(width 0.05)
				(type solid)
			)
			(layer "F.CrtYd")
		)
		(fp_line
			(start 1.75 -0.45)
			(end 1.75 0.45)
			(stroke
				(width 0.05)
				(type solid)
			)
			(layer "F.CrtYd")
		)
		(fp_line
			(start 0.825 -0.45)
			(end 1.75 -0.45)
			(stroke
				(width 0.05)
				(type solid)
			)
			(layer "F.CrtYd")
		)
		(fp_line
			(start 1.75 0.45)
			(end 0.85 0.45)
			(stroke
				(width 0.05)
				(type solid)
			)
			(layer "F.CrtYd")
		)
		(fp_line
			(start 0.85 0.45)
			(end 0.85 1.65)
			(stroke
				(width 0.05)
				(type solid)
			)
			(layer "F.CrtYd")
		)
		(fp_line
			(start -0.85 0.5)
			(end -0.85 -0.5)
			(stroke
				(width 0.05)
				(type solid)
			)
			(layer "F.CrtYd")
		)
		(fp_line
			(start -1.75 0.5)
			(end -0.85 0.5)
			(stroke
				(width 0.05)
				(type solid)
			)
			(layer "F.CrtYd")
		)
		(fp_line
			(start -0.85 1.4)
			(end -1.75 1.4)
			(stroke
				(width 0.05)
				(type solid)
			)
			(layer "F.CrtYd")
		)
		(fp_line
			(start -1.75 1.4)
			(end -1.75 0.5)
			(stroke
				(width 0.05)
				(type solid)
			)
			(layer "F.CrtYd")
		)
		(fp_line
			(start 0.85 1.65)
			(end -0.85 1.65)
			(stroke
				(width 0.05)
				(type solid)
			)
			(layer "F.CrtYd")
		)
		(fp_line
			(start -0.85 1.65)
			(end -0.85 1.4)
			(stroke
				(width 0.05)
				(type solid)
			)
			(layer "F.CrtYd")
		)
		(fp_line
			(start -0.437 -1.526)
			(end 0.688 -1.526)
			(stroke
				(width 0.15)
				(type solid)
			)
			(layer "F.Fab")
		)
		(fp_line
			(start -0.437 -1.526)
			(end -0.712 -1.325)
			(stroke
				(width 0.15)
				(type solid)
			)
			(layer "F.Fab")
		)
		(fp_line
			(start -0.712 -1.325)
			(end -0.712 1.523)
			(stroke
				(width 0.15)
				(type solid)
			)
			(layer "F.Fab")
		)
		(fp_line
			(start 0.688 1.519)
			(end 0.688 -1.52)
			(stroke
				(width 0.15)
				(type solid)
			)
			(layer "F.Fab")
		)
		(fp_line
			(start -0.712 1.519)
			(end 0.688 1.519)
			(stroke
				(width 0.15)
				(type solid)
			)
			(layer "F.Fab")
		)
		(pad "1" smd roundrect
			(at -1.1 -0.951 90)
			(size 1 0.6)
			(layers "F.Cu" "F.Mask" "F.Paste")
			(roundrect_rratio 0.15)
			(net 84 "/Com Express 7 MGMT/PWRBTN")
			(pinfunction "1")
			(pintype "passive")
			(teardrops
				(best_length_ratio 0.2)
				(max_length 1)
				(best_width_ratio 0.9)
				(max_width 2)
				(curved_edges yes)
				(filter_ratio 0.9)
				(enabled yes)
				(allow_two_segments yes)
				(prefer_zone_connections yes)
			)
		)
		(pad "2" smd roundrect
			(at -1.1 0.949 90)
			(size 1 0.6)
			(layers "F.Cu" "F.Mask" "F.Paste")
			(roundrect_rratio 0.15)
			(net 84 "/Com Express 7 MGMT/PWRBTN")
			(pinfunction "2")
			(pintype "passive")
			(teardrops
				(best_length_ratio 0.2)
				(max_length 1)
				(best_width_ratio 0.9)
				(max_width 2)
				(curved_edges yes)
				(filter_ratio 0.9)
				(enabled yes)
				(allow_two_segments yes)
				(prefer_zone_connections yes)
			)
		)
		(pad "3" smd roundrect
			(at 1.1 -0.0005 90)
			(size 1 0.6)
			(layers "F.Cu" "F.Mask" "F.Paste")
			(roundrect_rratio 0.15)
			(net 73 "+3V3_AON")
			(pinfunction "3")
			(pintype "passive")
			(teardrops
				(best_length_ratio 0.2)
				(max_length 1)
				(best_width_ratio 0.9)
				(max_width 2)
				(curved_edges yes)
				(filter_ratio 0.9)
				(enabled yes)
				(allow_two_segments yes)
				(prefer_zone_connections yes)
			)
		)
	)
	(footprint "antmicro-footprints:C_0402_1005Metric"
		(layer "F.Cu")
		(at 129.5 103.38 -90)
		(descr "Capacitor SMD 0402")
		(tags "capacitor SMD 0402")
		(property "Reference" "C13"
			(at -0.93 0.5 90)
			(layer "F.SilkS")
			(effects
				(font
					(size 0.7 0.7)
					(thickness 0.15)
				)
				(justify right bottom)
			)
		)
		(property "Value" "C_100n_0402"
			(at -1.022927 2.155213 90)
			(layer "F.Fab")
			(effects
				(font
					(size 0.7 0.7)
					(thickness 0.15)
				)
				(justify right bottom)
			)
		)
		(property "Datasheet" "https://www.murata.com/products/productdetail?partno=GRM155R61H104KE14%23"
			(at 0 0 270)
			(layer "F.Fab")
			(hide yes)
			(effects
				(font
					(size 1.27 1.27)
					(thickness 0.15)
				)
			)
		)
		(property "Author" "Antmicro"
			(at 26.12 232.88 0)
			(layer "F.Fab")
			(hide yes)
			(effects
				(font
					(size 1 1)
					(thickness 0.15)
				)
			)
		)
		(property "Dielectric" "X5R"
			(at 26.12 232.88 0)
			(layer "F.Fab")
			(hide yes)
			(effects
				(font
					(size 1 1)
					(thickness 0.15)
				)
			)
		)
		(property "License" "Apache-2.0"
			(at 26.12 232.88 0)
			(layer "F.Fab")
			(hide yes)
			(effects
				(font
					(size 1 1)
					(thickness 0.15)
				)
			)
		)
		(property "MPN" "GRM155R61H104KE14D"
			(at 26.12 232.88 0)
			(layer "F.Fab")
			(hide yes)
			(effects
				(font
					(size 1 1)
					(thickness 0.15)
				)
			)
		)
		(property "Manufacturer" "Murata"
			(at 26.12 232.88 0)
			(layer "F.Fab")
			(hide yes)
			(effects
				(font
					(size 1 1)
					(thickness 0.15)
				)
			)
		)
		(property "Public" "False"
			(at 26.12 232.88 0)
			(layer "F.Fab")
			(hide yes)
			(effects
				(font
					(size 1 1)
					(thickness 0.15)
				)
			)
		)
		(property "Val" "100n"
			(at 26.12 232.88 0)
			(layer "F.Fab")
			(hide yes)
			(effects
				(font
					(size 1 1)
					(thickness 0.15)
				)
			)
		)
		(property "Voltage" "50V"
			(at 26.12 232.88 0)
			(layer "F.Fab")
			(hide yes)
			(effects
				(font
					(size 1 1)
					(thickness 0.15)
				)
			)
		)
		(sheetname "2xUSB3.0+RJ45")
		(sheetfile "usb3+rj45.kicad_sch")
		(attr smd)
		(fp_rect
			(start -0.925 -0.47)
			(end 0.925 0.47)
			(stroke
				(width 0.05)
				(type default)
			)
			(fill no)
			(layer "F.CrtYd")
		)
		(fp_line
			(start -0.494 0.248)
			(end -0.494 -0.25)
			(stroke
				(width 0.15)
				(type solid)
			)
			(layer "F.Fab")
		)
		(fp_line
			(start 0.504 0.248)
			(end -0.494 0.248)
			(stroke
				(width 0.15)
				(type solid)
			)
			(layer "F.Fab")
		)
		(fp_line
			(start -0.494 -0.25)
			(end 0.504 -0.25)
			(stroke
				(width 0.15)
				(type solid)
			)
			(layer "F.Fab")
		)
		(fp_line
			(start 0.504 -0.25)
			(end 0.504 0.248)
			(stroke
				(width 0.15)
				(type solid)
			)
			(layer "F.Fab")
		)
		(pad "1" smd roundrect
			(at -0.48 0 270)
			(size 0.59 0.64)
			(layers "F.Cu" "F.Mask" "F.Paste")
			(roundrect_rratio 0.25)
			(net 51 "Net-(C13-Pad1)")
			(pintype "passive")
			(teardrops
				(best_length_ratio 0.2)
				(max_length 1)
				(best_width_ratio 0.9)
				(max_width 2)
				(curved_edges yes)
				(filter_ratio 0.9)
				(enabled yes)
				(allow_two_segments yes)
				(prefer_zone_connections yes)
			)
		)
		(pad "2" smd roundrect
			(at 0.48 0 270)
			(size 0.59 0.64)
			(layers "F.Cu" "F.Mask" "F.Paste")
			(roundrect_rratio 0.25)
			(net 1 "GND")
			(pintype "passive")
			(teardrops
				(best_length_ratio 0.2)
				(max_length 1)
				(best_width_ratio 0.9)
				(max_width 2)
				(curved_edges yes)
				(filter_ratio 0.9)
				(enabled yes)
				(allow_two_segments yes)
				(prefer_zone_connections yes)
			)
		)
	)
	(footprint "antmicro-footprints:R_0402_1005Metric"
		(layer "F.Cu")
		(at 308.05 139.96)
		(descr "Resistor SMD 0402")
		(tags "resistor SMD 0402")
		(property "Reference" "R94"
			(at -1.05 -0.45 0)
			(layer "F.SilkS")
			(effects
				(font
					(size 0.7 0.7)
					(thickness 0.15)
				)
				(justify left bottom)
			)
		)
		(property "Value" "R_100k_0402"
			(at -1.011843 1.772047 0)
			(layer "F.Fab")
			(effects
				(font
					(size 0.7 0.7)
					(thickness 0.15)
				)
				(justify left bottom)
			)
		)
		(property "Datasheet" "https://www.bourns.com/docs/product-datasheets/cr.pdf"
			(at 0 0 0)
			(layer "F.Fab")
			(hide yes)
			(effects
				(font
					(size 1.27 1.27)
					(thickness 0.15)
				)
			)
		)
		(property "Author" "Antmicro"
			(at 0 0 0)
			(layer "F.Fab")
			(hide yes)
			(effects
				(font
					(size 1 1)
					(thickness 0.15)
				)
			)
		)
		(property "License" "Apache-2.0"
			(at 0 0 0)
			(layer "F.Fab")
			(hide yes)
			(effects
				(font
					(size 1 1)
					(thickness 0.15)
				)
			)
		)
		(property "MPN" "CR0402-FX-1003GLF"
			(at 0 0 0)
			(layer "F.Fab")
			(hide yes)
			(effects
				(font
					(size 1 1)
					(thickness 0.15)
				)
			)
		)
		(property "Manufacturer" "Bourns"
			(at 0 0 0)
			(layer "F.Fab")
			(hide yes)
			(effects
				(font
					(size 1 1)
					(thickness 0.15)
				)
			)
		)
		(property "Public" "False"
			(at 0 0 0)
			(layer "F.Fab")
			(hide yes)
			(effects
				(font
					(size 1 1)
					(thickness 0.15)
				)
			)
		)
		(property "Tolerance" "1%"
			(at 0 0 0)
			(layer "F.Fab")
			(hide yes)
			(effects
				(font
					(size 1 1)
					(thickness 0.15)
				)
			)
		)
		(property "Val" "100k"
			(at 0 0 0)
			(layer "F.Fab")
			(hide yes)
			(effects
				(font
					(size 1 1)
					(thickness 0.15)
				)
			)
		)
		(sheetname "Power")
		(sheetfile "power.kicad_sch")
		(attr smd)
		(fp_rect
			(start -0.925 -0.47)
			(end 0.925 0.47)
			(stroke
				(width 0.05)
				(type default)
			)
			(fill no)
			(layer "F.CrtYd")
		)
		(fp_rect
			(start -0.5 -0.25)
			(end 0.5 0.25)
			(stroke
				(width 0.15)
				(type solid)
			)
			(fill no)
			(layer "F.Fab")
		)
		(pad "1" smd roundrect
			(at -0.48 0)
			(size 0.59 0.64)
			(layers "F.Cu" "F.Mask" "F.Paste")
			(roundrect_rratio 0.25)
			(net 534 "Net-(Q1-D)")
			(pintype "passive")
			(teardrops
				(best_length_ratio 0.2)
				(max_length 1)
				(best_width_ratio 0.9)
				(max_width 2)
				(curved_edges yes)
				(filter_ratio 0.9)
				(enabled yes)
				(allow_two_segments yes)
				(prefer_zone_connections yes)
			)
		)
		(pad "2" smd roundrect
			(at 0.48 0)
			(size 0.59 0.64)
			(layers "F.Cu" "F.Mask" "F.Paste")
			(roundrect_rratio 0.25)
			(net 62 "+12V_AON")
			(pintype "passive")
			(teardrops
				(best_length_ratio 0.2)
				(max_length 1)
				(best_width_ratio 0.9)
				(max_width 2)
				(curved_edges yes)
				(filter_ratio 0.9)
				(enabled yes)
				(allow_two_segments yes)
				(prefer_zone_connections yes)
			)
		)
	)
)
